# BASEBOARD_FAB2 (Tioga Pass) — schematic netlist excerpt (pin names and nets, part order shuffled) for the footprints in the layout excerpt that follows; sources: Cadence DE-HDL packaged netlist, KiCad conversion of Wiwynn_Tioga_Pass_MB.brd

R3P49  RES  100.0 1% CHIP  pkg 0402  page 92 : A = P0V7_GTL2104_VREF_1 ; B = GND
C6P12  CAP_A  0.1UF 16V 10% X7R  pkg 0402V  page 102 : A = P3V3_DB1200 ; B = GND
R8E17  RES  33.2 1% CHIP  pkg 0402  page 142 : A = IRQ_LVC3_WAKE_R_N ; B = IRQ_LVC3_WAKE_N

(kicad_pcb
	(version 20260206)
	(generator "pcbnew")
	(generator_version "10.0")
	(general
		(thickness 1.6)
		(legacy_teardrops no)
	)
	(paper "A4")
	(title_block
		(title "Wiwynn_Tioga_Pass_MB.brd")
		(comment 1 "Tioga Pass / footprints 4706-4708 of 4770")
	)
	(layers
		(0 "F.Cu" signal "TOP")
		(4 "In1.Cu" signal "L2GND")
		(6 "In2.Cu" signal "L3")
		(8 "In3.Cu" signal "L4GND")
		(10 "In4.Cu" signal "L5")
		(12 "In5.Cu" signal "L6GND")
		(14 "In6.Cu" signal "L7VCC")
		(16 "In7.Cu" signal "L8VCC")
		(18 "In8.Cu" signal "L9GND")
		(20 "In9.Cu" signal "L10")
		(22 "In10.Cu" signal "L11GND")
		(24 "In11.Cu" signal "L12")
		(26 "In12.Cu" signal "L13GND")
		(2 "B.Cu" signal "BOTTOM")
		(9 "F.Adhes" user "F.Adhesive")
		(11 "B.Adhes" user "B.Adhesive")
		(13 "F.Paste" user "Package Geometry/Pastemask Top")
		(15 "B.Paste" user "Package Geometry/Pastemask Bottom")
		(5 "F.SilkS" user "Ref Des/Silkscreen Top")
		(7 "B.SilkS" user "Ref Des/Silkscreen Bottom")
		(1 "F.Mask" user "Board Geometry/Soldermask Top")
		(3 "B.Mask" user "Board Geometry/Soldermask Bottom")
		(17 "Dwgs.User" user "User.Drawings")
		(19 "Cmts.User" user "User.Comments")
		(21 "Eco1.User" user "User.Eco1")
		(23 "Eco2.User" user "User.Eco2")
		(25 "Edge.Cuts" user "Board Geometry/Outline")
		(27 "Margin" user)
		(31 "F.CrtYd" user "Package Geometry/Place Bound Top")
		(29 "B.CrtYd" user "Package Geometry/Place Bound Bottom")
		(35 "F.Fab" user "Ref Des/Assembly Top")
		(33 "B.Fab" user "Ref Des/Assembly Bottom")
	)
	(footprint ""
		(layer "B.Cu")
		(at 373.520716 -59.289442 180)
		(property "Reference" "R3P49"
			(at 0 0 0)
			(layer "B.SilkS")
			(hide yes)
			(effects
				(font
					(size 1.27 1.27)
				)
				(justify mirror)
			)
		)
		(property "Value" ""
			(at 0 0 0)
			(layer "B.Fab")
			(effects
				(font
					(size 1.27 1.27)
				)
				(justify mirror)
			)
		)
		(duplicate_pad_numbers_are_jumpers no)
		(fp_poly
			(pts
				(xy 0.2794 -0.1016) (xy -0.2794 -0.1016) (xy -0.2794 0.9906) (xy 0.2794 0.9906)
			)
			(stroke
				(width 0)
				(type default)
			)
			(fill no)
			(layer "B.CrtYd")
		)
		(fp_line
			(start 0.2794 0.9906)
			(end -0.2794 0.9906)
			(stroke
				(width 0.1)
				(type default)
			)
			(layer "B.Fab")
		)
		(fp_line
			(start 0.2794 -0.1016)
			(end 0.2794 0.9906)
			(stroke
				(width 0.1)
				(type default)
			)
			(layer "B.Fab")
		)
		(fp_line
			(start -0.2794 0.9906)
			(end -0.2794 -0.1016)
			(stroke
				(width 0.1)
				(type default)
			)
			(layer "B.Fab")
		)
		(fp_line
			(start -0.2794 -0.1016)
			(end 0.2794 -0.1016)
			(stroke
				(width 0.1)
				(type default)
			)
			(layer "B.Fab")
		)
		(pad "1" smd rect
			(at 0 0)
			(size 0.508 0.508)
			(layers "B.Cu" "B.Mask" "B.Paste")
			(net "P0V7_GTL2104_VREF_1")
		)
		(pad "2" smd rect
			(at 0 0.889)
			(size 0.508 0.508)
			(layers "B.Cu" "B.Mask" "B.Paste")
			(net "GND")
		)
		(zone
			(layer "B.Cu")
			(hatch none 0.5)
			(connect_pads
				(clearance 0)
			)
			(min_thickness 0.25)
			(keepout
				(tracks not_allowed)
				(vias allowed)
				(pads allowed)
				(copperpour not_allowed)
				(footprints allowed)
			)
			(placement
				(enabled no)
				(sheetname "")
			)
			(fill
				(thermal_gap 0.5)
				(thermal_bridge_width 0.5)
				(island_removal_mode 0)
			)
			(polygon
				(pts
					(xy 373.266716 -59.924442) (xy 373.774716 -59.924442) (xy 373.774716 -59.543442) (xy 373.266716 -59.543442)
				)
			)
		)
		(zone
			(layer "B.Cu")
			(hatch none 0.5)
			(connect_pads
				(clearance 0)
			)
			(min_thickness 0.25)
			(keepout
				(tracks allowed)
				(vias not_allowed)
				(pads allowed)
				(copperpour not_allowed)
				(footprints allowed)
			)
			(placement
				(enabled no)
				(sheetname "")
			)
			(fill
				(thermal_gap 0.5)
				(thermal_bridge_width 0.5)
				(island_removal_mode 0)
			)
			(polygon
				(pts
					(xy 373.266716 -59.543442) (xy 373.774716 -59.543442) (xy 373.774716 -59.924442) (xy 373.266716 -59.924442)
				)
			)
		)
	)
	(footprint ""
		(layer "B.Cu")
		(at 164.973 -80.391 90)
		(property "Reference" "C6P12"
			(at 0 0 90)
			(layer "B.SilkS")
			(hide yes)
			(effects
				(font
					(size 1.27 1.27)
				)
				(justify mirror)
			)
		)
		(property "Value" ""
			(at 0 0 90)
			(layer "B.Fab")
			(effects
				(font
					(size 1.27 1.27)
				)
				(justify mirror)
			)
		)
		(duplicate_pad_numbers_are_jumpers no)
		(fp_poly
			(pts
				(xy -0.3048 -0.1016) (xy -0.3048 0.9906) (xy 0.3048 0.9906) (xy 0.3048 -0.1016)
			)
			(stroke
				(width 0)
				(type default)
			)
			(fill no)
			(layer "B.CrtYd")
		)
		(fp_line
			(start 0.3048 -0.1016)
			(end 0.3048 0.9906)
			(stroke
				(width 0.1)
				(type default)
			)
			(layer "B.Fab")
		)
		(fp_line
			(start -0.3048 -0.1016)
			(end 0.3048 -0.1016)
			(stroke
				(width 0.1)
				(type default)
			)
			(layer "B.Fab")
		)
		(fp_line
			(start 0.3048 0.9906)
			(end -0.3048 0.9906)
			(stroke
				(width 0.1)
				(type default)
			)
			(layer "B.Fab")
		)
		(fp_line
			(start -0.3048 0.9906)
			(end -0.3048 -0.1016)
			(stroke
				(width 0.1)
				(type default)
			)
			(layer "B.Fab")
		)
		(pad "1" smd rect
			(at 0 0 270)
			(size 0.508 0.508)
			(layers "B.Cu" "B.Mask" "B.Paste")
			(net "P3V3_DB1200")
		)
		(pad "2" smd rect
			(at 0 0.889 270)
			(size 0.508 0.508)
			(layers "B.Cu" "B.Mask" "B.Paste")
			(net "GND")
		)
		(zone
			(layer "B.Cu")
			(hatch none 0.5)
			(connect_pads
				(clearance 0)
			)
			(min_thickness 0.25)
			(keepout
				(tracks allowed)
				(vias not_allowed)
				(pads allowed)
				(copperpour not_allowed)
				(footprints allowed)
			)
			(placement
				(enabled no)
				(sheetname "")
			)
			(fill
				(thermal_gap 0.5)
				(thermal_bridge_width 0.5)
				(island_removal_mode 0)
			)
			(polygon
				(pts
					(xy 165.227 -80.645) (xy 165.227 -80.137) (xy 165.608 -80.137) (xy 165.608 -80.645)
				)
			)
		)
		(zone
			(layer "B.Cu")
			(hatch none 0.5)
			(connect_pads
				(clearance 0)
			)
			(min_thickness 0.25)
			(keepout
				(tracks not_allowed)
				(vias allowed)
				(pads allowed)
				(copperpour not_allowed)
				(footprints allowed)
			)
			(placement
				(enabled no)
				(sheetname "")
			)
			(fill
				(thermal_gap 0.5)
				(thermal_bridge_width 0.5)
				(island_removal_mode 0)
			)
			(polygon
				(pts
					(xy 165.608 -80.645) (xy 165.608 -80.137) (xy 165.227 -80.137) (xy 165.227 -80.645)
				)
			)
		)
	)
	(footprint ""
		(layer "B.Cu")
		(at 482.727 -53.1368 -90)
		(property "Reference" "R8E17"
			(at 0 0 90)
			(layer "B.SilkS")
			(hide yes)
			(effects
				(font
					(size 1.27 1.27)
				)
				(justify mirror)
			)
		)
		(property "Value" ""
			(at 0 0 90)
			(layer "B.Fab")
			(effects
				(font
					(size 1.27 1.27)
				)
				(justify mirror)
			)
		)
		(duplicate_pad_numbers_are_jumpers no)
		(fp_poly
			(pts
				(xy 0.2794 -0.1016) (xy -0.2794 -0.1016) (xy -0.2794 0.9906) (xy 0.2794 0.9906)
			)
			(stroke
				(width 0)
				(type default)
			)
			(fill no)
			(layer "B.CrtYd")
		)
		(fp_line
			(start -0.2794 0.9906)
			(end -0.2794 -0.1016)
			(stroke
				(width 0.1)
				(type default)
			)
			(layer "B.Fab")
		)
		(fp_line
			(start 0.2794 0.9906)
			(end -0.2794 0.9906)
			(stroke
				(width 0.1)
				(type default)
			)
			(layer "B.Fab")
		)
		(fp_line
			(start -0.2794 -0.1016)
			(end 0.2794 -0.1016)
			(stroke
				(width 0.1)
				(type default)
			)
			(layer "B.Fab")
		)
		(fp_line
			(start 0.2794 -0.1016)
			(end 0.2794 0.9906)
			(stroke
				(width 0.1)
				(type default)
			)
			(layer "B.Fab")
		)
		(pad "1" smd rect
			(at 0 0 90)
			(size 0.508 0.508)
			(layers "B.Cu" "B.Mask" "B.Paste")
			(net "IRQ_LVC3_WAKE_R_N")
		)
		(pad "2" smd rect
			(at 0 0.889 90)
			(size 0.508 0.508)
			(layers "B.Cu" "B.Mask" "B.Paste")
			(net "IRQ_LVC3_WAKE_N")
		)
		(zone
			(layer "B.Cu")
			(hatch none 0.5)
			(connect_pads
				(clearance 0)
			)
			(min_thickness 0.25)
			(keepout
				(tracks not_allowed)
				(vias allowed)
				(pads allowed)
				(copperpour not_allowed)
				(footprints allowed)
			)
			(placement
				(enabled no)
				(sheetname "")
			)
			(fill
				(thermal_gap 0.5)
				(thermal_bridge_width 0.5)
				(island_removal_mode 0)
			)
			(polygon
				(pts
					(xy 482.092 -52.8828) (xy 482.092 -53.3908) (xy 482.473 -53.3908) (xy 482.473 -52.8828)
				)
			)
		)
		(zone
			(layer "B.Cu")
			(hatch none 0.5)
			(connect_pads
				(clearance 0)
			)
			(min_thickness 0.25)
			(keepout
				(tracks allowed)
				(vias not_allowed)
				(pads allowed)
				(copperpour not_allowed)
				(footprints allowed)
			)
			(placement
				(enabled no)
				(sheetname "")
			)
			(fill
				(thermal_gap 0.5)
				(thermal_bridge_width 0.5)
				(island_removal_mode 0)
			)
			(polygon
				(pts
					(xy 482.473 -52.8828) (xy 482.473 -53.3908) (xy 482.092 -53.3908) (xy 482.092 -52.8828)
				)
			)
		)
	)
)
